# T6G (Grand Teton) — schematic netlist excerpt (pin names and nets, part order shuffled) for the footprints in the layout excerpt that follows; sources: Cadence DE-HDL packaged netlist, KiCad conversion of 04192023_DAF0TMB3IC0_F0TG_MB_C_brd_V02_OCP.brd

PC8000  Q_CAP  22UF 16V 20% X6S  pkg C0805  page 192 : A = SW_P12V_AUX_PVDD_33_S5_FLT ; B = GND
PC335_2  Q_CAP  22UF 16V 20% X6S  pkg C0805  page 215 : A = SW_P12V_AUX_PVDDCR_SOC_P1_FLT ; B = GND
C569  Q_CAP  4.7UF 6.3V 20% X6S  pkg 0402  page 279 : A = P0V9_CPU0_RT_2D ; B = GND

(kicad_pcb
	(version 20260206)
	(generator "pcbnew")
	(generator_version "10.0")
	(general
		(thickness 1.6)
		(legacy_teardrops no)
	)
	(paper "A4")
	(title_block
		(title "04192023_DAF0TMB3IC0_F0TG_MB_C_brd_V02_OCP.brd")
		(comment 1 "Grand Teton / footprints 7115-7117 of 8354")
	)
	(layers
		(0 "F.Cu" signal "TOP")
		(4 "In1.Cu" signal "GND")
		(6 "In2.Cu" signal "IN1")
		(8 "In3.Cu" signal "GND1")
		(10 "In4.Cu" signal "IN2")
		(12 "In5.Cu" signal "GND2")
		(14 "In6.Cu" signal "IN3")
		(16 "In7.Cu" signal "GND3")
		(18 "In8.Cu" signal "VCC")
		(20 "In9.Cu" signal "VCC1")
		(22 "In10.Cu" signal "GND4")
		(24 "In11.Cu" signal "IN4")
		(26 "In12.Cu" signal "GND5")
		(28 "In13.Cu" signal "IN5")
		(30 "In14.Cu" signal "GND6")
		(32 "In15.Cu" signal "IN6")
		(34 "In16.Cu" signal "GND7")
		(2 "B.Cu" signal "BOTTOM")
		(9 "F.Adhes" user "F.Adhesive")
		(11 "B.Adhes" user "B.Adhesive")
		(13 "F.Paste" user "Package Geometry/Pastemask Top")
		(15 "B.Paste" user "Package Geometry/Pastemask Bottom")
		(5 "F.SilkS" user "Ref Des/Silkscreen Top")
		(7 "B.SilkS" user "Ref Des/Silkscreen Bottom")
		(1 "F.Mask" user "Board Geometry/Soldermask Top")
		(3 "B.Mask" user "Board Geometry/Soldermask Bottom")
		(17 "Dwgs.User" user "User.Drawings")
		(19 "Cmts.User" user "User.Comments")
		(21 "Eco1.User" user "User.Eco1")
		(23 "Eco2.User" user "User.Eco2")
		(25 "Edge.Cuts" user "Board Geometry/Outline")
		(27 "Margin" user)
		(31 "F.CrtYd" user "Package Geometry/Place Bound Top")
		(29 "B.CrtYd" user "Package Geometry/Place Bound Bottom")
		(35 "F.Fab" user "Ref Des/Assembly Top")
		(33 "B.Fab" user "Ref Des/Assembly Bottom")
	)
	(footprint ""
		(layer "B.Cu")
		(at 309.39105 -398.942052 90)
		(property "Reference" "C569"
			(at 0 0 90)
			(layer "B.SilkS")
			(hide yes)
			(effects
				(font
					(size 1.27 1.27)
				)
				(justify mirror)
			)
		)
		(property "Value" ""
			(at 0 0 90)
			(layer "B.Fab")
			(effects
				(font
					(size 1.27 1.27)
				)
				(justify mirror)
			)
		)
		(duplicate_pad_numbers_are_jumpers no)
		(fp_line
			(start 0.7874 -0.4064)
			(end -0.7874 -0.4064)
			(stroke
				(width 0.1524)
				(type default)
			)
			(layer "B.SilkS")
		)
		(fp_line
			(start -0.7874 -0.4064)
			(end -0.7874 0.4064)
			(stroke
				(width 0.1524)
				(type default)
			)
			(layer "B.SilkS")
		)
		(fp_line
			(start 0.7874 0.4064)
			(end 0.7874 -0.4064)
			(stroke
				(width 0.1524)
				(type default)
			)
			(layer "B.SilkS")
		)
		(fp_line
			(start -0.7874 0.4064)
			(end 0.7874 0.4064)
			(stroke
				(width 0.1524)
				(type default)
			)
			(layer "B.SilkS")
		)
		(fp_line
			(start 0.67945 -0.305054)
			(end 0.12065 -0.305054)
			(stroke
				(width 0.1)
				(type default)
			)
			(layer "B.Fab")
		)
		(fp_line
			(start 0.12065 -0.305054)
			(end 0.12065 -0.2794)
			(stroke
				(width 0.1)
				(type default)
			)
			(layer "B.Fab")
		)
		(fp_line
			(start -0.12065 -0.3048)
			(end -0.67945 -0.3048)
			(stroke
				(width 0.1)
				(type default)
			)
			(layer "B.Fab")
		)
		(fp_line
			(start -0.67945 -0.3048)
			(end -0.67945 0.3048)
			(stroke
				(width 0.1)
				(type default)
			)
			(layer "B.Fab")
		)
		(fp_line
			(start 0.12065 -0.2794)
			(end -0.12065 -0.2794)
			(stroke
				(width 0.1)
				(type default)
			)
			(layer "B.Fab")
		)
		(fp_line
			(start -0.12065 -0.2794)
			(end -0.12065 -0.3048)
			(stroke
				(width 0.1)
				(type default)
			)
			(layer "B.Fab")
		)
		(fp_line
			(start 0.12065 0.2794)
			(end 0.12065 0.3048)
			(stroke
				(width 0.1)
				(type default)
			)
			(layer "B.Fab")
		)
		(fp_line
			(start -0.120396 0.2794)
			(end 0.12065 0.2794)
			(stroke
				(width 0.1)
				(type default)
			)
			(layer "B.Fab")
		)
		(fp_line
			(start 0.67945 0.3048)
			(end 0.67945 -0.305054)
			(stroke
				(width 0.1)
				(type default)
			)
			(layer "B.Fab")
		)
		(fp_line
			(start 0.12065 0.3048)
			(end 0.67945 0.3048)
			(stroke
				(width 0.1)
				(type default)
			)
			(layer "B.Fab")
		)
		(fp_line
			(start -0.120396 0.3048)
			(end -0.120396 0.2794)
			(stroke
				(width 0.1)
				(type default)
			)
			(layer "B.Fab")
		)
		(fp_line
			(start -0.67945 0.3048)
			(end -0.120396 0.3048)
			(stroke
				(width 0.1)
				(type default)
			)
			(layer "B.Fab")
		)
		(pad "1" smd circle
			(at 0.40005 0 270)
			(size 0 0)
			(layers "B.Cu" "B.Mask" "B.Paste")
			(net "P0V9_CPU0_RT_2D")
		)
		(pad "2" smd circle
			(at -0.40005 0 270)
			(size 0 0)
			(layers "B.Cu" "B.Mask" "B.Paste")
			(net "GND")
		)
	)
	(footprint ""
		(layer "B.Cu")
		(at 199.941942 -346.023184)
		(property "Reference" "PC8000"
			(at 0 0 0)
			(layer "B.SilkS")
			(hide yes)
			(effects
				(font
					(size 1.27 1.27)
				)
				(justify mirror)
			)
		)
		(property "Value" ""
			(at 0 0 0)
			(layer "B.Fab")
			(effects
				(font
					(size 1.27 1.27)
				)
				(justify mirror)
			)
		)
		(duplicate_pad_numbers_are_jumpers no)
		(fp_line
			(start -1.524 -0.762)
			(end -1.524 0.762)
			(stroke
				(width 0.1524)
				(type default)
			)
			(layer "B.SilkS")
		)
		(fp_line
			(start -1.524 0.762)
			(end 1.524 0.762)
			(stroke
				(width 0.1524)
				(type default)
			)
			(layer "B.SilkS")
		)
		(fp_line
			(start 1.524 -0.762)
			(end -1.524 -0.762)
			(stroke
				(width 0.1524)
				(type default)
			)
			(layer "B.SilkS")
		)
		(fp_line
			(start 1.524 0.762)
			(end 1.524 -0.762)
			(stroke
				(width 0.1524)
				(type default)
			)
			(layer "B.SilkS")
		)
		(fp_line
			(start -1.1049 -0.724916)
			(end 1.1049 -0.724916)
			(stroke
				(width 0.1)
				(type default)
			)
			(layer "B.Fab")
		)
		(fp_line
			(start -1.1049 0.724916)
			(end -1.1049 -0.724916)
			(stroke
				(width 0.1)
				(type default)
			)
			(layer "B.Fab")
		)
		(fp_line
			(start 1.1049 -0.724916)
			(end 1.1049 0.724916)
			(stroke
				(width 0.1)
				(type default)
			)
			(layer "B.Fab")
		)
		(fp_line
			(start 1.1049 0.724916)
			(end -1.1049 0.724916)
			(stroke
				(width 0.1)
				(type default)
			)
			(layer "B.Fab")
		)
		(pad "1" smd rect
			(at 0.889 0)
			(size 1.016 1.27)
			(layers "B.Cu" "B.Mask" "B.Paste")
			(net "SW_P12V_AUX_PVDD_33_S5_FLT")
		)
		(pad "2" smd rect
			(at -0.889 0)
			(size 1.016 1.27)
			(layers "B.Cu" "B.Mask" "B.Paste")
			(net "GND")
		)
	)
	(footprint ""
		(layer "B.Cu")
		(at 119.103648 -165.079934 -90)
		(property "Reference" "PC335_2"
			(at 0 0 90)
			(layer "B.SilkS")
			(hide yes)
			(effects
				(font
					(size 1.27 1.27)
				)
				(justify mirror)
			)
		)
		(property "Value" ""
			(at 0 0 90)
			(layer "B.Fab")
			(effects
				(font
					(size 1.27 1.27)
				)
				(justify mirror)
			)
		)
		(duplicate_pad_numbers_are_jumpers no)
		(fp_line
			(start -1.524 0.762)
			(end 1.524 0.762)
			(stroke
				(width 0.1524)
				(type default)
			)
			(layer "B.SilkS")
		)
		(fp_line
			(start 1.524 0.762)
			(end 1.524 -0.762)
			(stroke
				(width 0.1524)
				(type default)
			)
			(layer "B.SilkS")
		)
		(fp_line
			(start -1.524 -0.762)
			(end -1.524 0.762)
			(stroke
				(width 0.1524)
				(type default)
			)
			(layer "B.SilkS")
		)
		(fp_line
			(start 1.524 -0.762)
			(end -1.524 -0.762)
			(stroke
				(width 0.1524)
				(type default)
			)
			(layer "B.SilkS")
		)
		(fp_line
			(start -1.1049 0.724916)
			(end -1.1049 -0.724916)
			(stroke
				(width 0.1)
				(type default)
			)
			(layer "B.Fab")
		)
		(fp_line
			(start 1.1049 0.724916)
			(end -1.1049 0.724916)
			(stroke
				(width 0.1)
				(type default)
			)
			(layer "B.Fab")
		)
		(fp_line
			(start -1.1049 -0.724916)
			(end 1.1049 -0.724916)
			(stroke
				(width 0.1)
				(type default)
			)
			(layer "B.Fab")
		)
		(fp_line
			(start 1.1049 -0.724916)
			(end 1.1049 0.724916)
			(stroke
				(width 0.1)
				(type default)
			)
			(layer "B.Fab")
		)
		(pad "1" smd rect
			(at 0.889 0 270)
			(size 1.016 1.27)
			(layers "B.Cu" "B.Mask" "B.Paste")
			(net "SW_P12V_AUX_PVDDCR_SOC_P1_FLT")
		)
		(pad "2" smd rect
			(at -0.889 0 270)
			(size 1.016 1.27)
			(layers "B.Cu" "B.Mask" "B.Paste")
			(net "GND")
		)
	)
)
